(kicad_pcb
	(version 20211014)
	(generator pcbnew)
	(general
    (thickness 1.6)
  )
	(paper "A4")
	(title_block
    (title "SA800U (Snapdragon 845) Baseboard")
    (date "2023-10-19")
    (rev "1.0.3")
    (company "Antmicro Ltd.")
    (comment 1 "www.antmicro.com")
		(comment 9 "footprints 105-109 of 589")
	)
	(layers
    (0 "F.Cu" signal)
    (1 "In1.Cu" power)
    (2 "In2.Cu" signal)
    (3 "In3.Cu" signal)
    (4 "In4.Cu" power)
    (31 "B.Cu" signal)
    (32 "B.Adhes" user "B.Adhesive")
    (33 "F.Adhes" user "F.Adhesive")
    (34 "B.Paste" user)
    (35 "F.Paste" user)
    (36 "B.SilkS" user "B.Silkscreen")
    (37 "F.SilkS" user "F.Silkscreen")
    (38 "B.Mask" user)
    (39 "F.Mask" user)
    (40 "Dwgs.User" user "User.Drawings")
    (41 "Cmts.User" user "User.Comments")
    (42 "Eco1.User" user "User.Eco1")
    (43 "Eco2.User" user "User.Eco2")
    (44 "Edge.Cuts" user)
    (45 "Margin" user)
    (46 "B.CrtYd" user "B.Courtyard")
    (47 "F.CrtYd" user "F.Courtyard")
    (48 "B.Fab" user)
    (49 "F.Fab" user)
  )
	(footprint "sa800u-baseboard-hw-footprints:USB-C_12401610E4_2A" locked (layer "F.Cu")
    (tedit 6215EC4A)
    (at 129.75 147.95)
    (property "Author" "Antmicro")
    (property "License" "Apache-2.0")
    (property "MPN" "12401598E4#2A")
    (property "Manufacturer" "Amphenol")
    (property "Sheetfile" "usb-c-interface.kicad_sch")
    (property "Sheetname" "USB-C Interface ")
    (attr smd)
    (fp_text reference "J5" (at 3.42 -5.58) (layer "F.SilkS")
      (effects (font (size 0.7 0.7) (thickness 0.15)) (justify left bottom))
    )
    (fp_text value "12401598E4_2A" (at 0 6.549) (layer "F.Fab")
      (effects (font (size 0.7 0.7) (thickness 0.15)) (justify left bottom))
    )
    (fp_text user "${REFERENCE}" (at -4.901 8.55) (layer "F.Fab") hide
      (effects (font (size 0.7 0.7) (thickness 0.15)) (justify left bottom))
    )
    (fp_text user "License: Apache-2.0" (at -4.901 10.948) (layer "F.Fab") hide
      (effects (font (size 0.7 0.7) (thickness 0.15)) (justify left bottom))
    )
    (fp_text user "Author: Antmicro" (at -4.901 9.749) (layer "F.Fab") hide
      (effects (font (size 0.7 0.7) (thickness 0.15)) (justify left bottom))
    )
    (fp_line (start 4.599 5.448) (end 4.099 5.448) (layer "F.SilkS") (width 0.15))
    (fp_line (start 4.599 -5.25) (end 4.099 -5.25) (layer "F.SilkS") (width 0.15))
    (fp_line (start -4.601 5.448) (end -4.1 5.448) (layer "F.SilkS") (width 0.15))
    (fp_line (start 4.599 5.448) (end 4.599 4.948) (layer "F.SilkS") (width 0.15))
    (fp_line (start -4.601 -5.25) (end -4.601 -4.75) (layer "F.SilkS") (width 0.15))
    (fp_line (start -4.601 -5.25) (end -4.1 -5.25) (layer "F.SilkS") (width 0.15))
    (fp_line (start -4.601 5.448) (end -4.601 4.948) (layer "F.SilkS") (width 0.15))
    (fp_line (start 4.599 -5.25) (end 4.599 -4.75) (layer "F.SilkS") (width 0.15))
    (fp_circle (center -3.101 -5.25) (end -3.052 -5.25) (layer "F.SilkS") (width 0.15) (fill solid))
    (fp_rect (start -4.92 -5.46) (end 4.9 5.44) (layer "F.CrtYd") (width 0.05) (fill none))
    (fp_line (start -4.491 5.339) (end 4.49 5.339) (layer "F.Fab") (width 0.15))
    (fp_line (start -4.491 -5.162) (end 4.49 -5.162) (layer "F.Fab") (width 0.15))
    (fp_line (start 4.49 -5.162) (end 4.49 5.339) (layer "F.Fab") (width 0.15))
    (fp_line (start -4.491 -5.162) (end -4.491 5.339) (layer "F.Fab") (width 0.15))
    (pad "" np_thru_hole circle locked (at -3.601 -4.25) (size 0.65 0.65) (drill 0.65) (layers *.Cu *.Mask))
    (pad "" np_thru_hole oval locked (at 3.6 -4.25) (size 0.95 0.65) (drill oval 0.95 0.65) (layers *.Cu *.Mask))
    (pad "A1" smd rect locked (at -2.75 -4.912) (size 0.3 0.7) (layers "F.Cu" "F.Paste" "F.Mask")
      (net 1 "GND") (pintype "passive"))
    (pad "A2" smd rect locked (at -2.25 -4.912) (size 0.3 0.7) (layers "F.Cu" "F.Paste" "F.Mask")
      (net 438 "unconnected-(J5-PadA2)") (pintype "passive+no_connect"))
    (pad "A3" smd rect locked (at -1.75 -4.912) (size 0.3 0.7) (layers "F.Cu" "F.Paste" "F.Mask")
      (net 437 "unconnected-(J5-PadA3)") (pintype "passive+no_connect"))
    (pad "A4" smd rect locked (at -1.25 -4.912) (size 0.3 0.7) (layers "F.Cu" "F.Paste" "F.Mask")
      (net 253 "/USB-C Interface /DBG_VBUS") (pintype "passive"))
    (pad "A5" smd rect locked (at -0.75 -4.912) (size 0.3 0.7) (layers "F.Cu" "F.Paste" "F.Mask")
      (net 436 "unconnected-(J5-PadA5)") (pintype "passive+no_connect"))
    (pad "A6" smd rect locked (at -0.25 -4.912) (size 0.3 0.7) (layers "F.Cu" "F.Paste" "F.Mask")
      (net 230 "/USB-C Interface /DBG_USB_D_P") (pintype "passive"))
    (pad "A7" smd rect locked (at 0.247 -4.912) (size 0.3 0.7) (layers "F.Cu" "F.Paste" "F.Mask")
      (net 229 "/USB-C Interface /DBG_USB_D_N") (pintype "passive"))
    (pad "A8" smd rect locked (at 0.747 -4.912) (size 0.3 0.7) (layers "F.Cu" "F.Paste" "F.Mask")
      (net 435 "unconnected-(J5-PadA8)") (pintype "passive+no_connect"))
    (pad "A9" smd rect locked (at 1.249 -4.912) (size 0.3 0.7) (layers "F.Cu" "F.Paste" "F.Mask")
      (net 253 "/USB-C Interface /DBG_VBUS") (pintype "passive"))
    (pad "A10" smd rect locked (at 1.749 -4.912) (size 0.3 0.7) (layers "F.Cu" "F.Paste" "F.Mask")
      (net 434 "unconnected-(J5-PadA10)") (pintype "passive+no_connect"))
    (pad "A11" smd rect locked (at 2.249 -4.912) (size 0.3 0.7) (layers "F.Cu" "F.Paste" "F.Mask")
      (net 433 "unconnected-(J5-PadA11)") (pintype "passive+no_connect"))
    (pad "A12" smd rect locked (at 2.749 -4.912) (size 0.3 0.7) (layers "F.Cu" "F.Paste" "F.Mask")
      (net 1 "GND") (pintype "passive"))
    (pad "B1" smd rect locked (at 2.499 -3.21) (size 0.3 0.7) (layers "F.Cu" "F.Paste" "F.Mask")
      (net 1 "GND") (pintype "passive"))
    (pad "B2" smd rect locked (at 1.999 -3.21) (size 0.3 0.7) (layers "F.Cu" "F.Paste" "F.Mask")
      (net 432 "unconnected-(J5-PadB2)") (pintype "passive+no_connect"))
    (pad "B3" smd rect locked (at 1.499 -3.21) (size 0.3 0.7) (layers "F.Cu" "F.Paste" "F.Mask")
      (net 431 "unconnected-(J5-PadB3)") (pintype "passive+no_connect"))
    (pad "B4" smd rect locked (at 0.997 -3.21) (size 0.3 0.7) (layers "F.Cu" "F.Paste" "F.Mask")
      (net 253 "/USB-C Interface /DBG_VBUS") (pintype "passive"))
    (pad "B5" smd rect locked (at 0.497 -3.21) (size 0.3 0.7) (layers "F.Cu" "F.Paste" "F.Mask")
      (net 430 "unconnected-(J5-PadB5)") (pintype "passive+no_connect"))
    (pad "B6" smd rect locked (at 0 -3.21) (size 0.3 0.7) (layers "F.Cu" "F.Paste" "F.Mask")
      (net 230 "/USB-C Interface /DBG_USB_D_P") (pintype "passive"))
    (pad "B7" smd rect locked (at -0.5 -3.21) (size 0.3 0.7) (layers "F.Cu" "F.Paste" "F.Mask")
      (net 229 "/USB-C Interface /DBG_USB_D_N") (pintype "passive"))
    (pad "B8" smd rect locked (at -1 -3.21) (size 0.3 0.7) (layers "F.Cu" "F.Paste" "F.Mask")
      (net 429 "unconnected-(J5-PadB8)") (pintype "passive+no_connect"))
    (pad "B9" smd rect locked (at -1.5 -3.21) (size 0.3 0.7) (layers "F.Cu" "F.Paste" "F.Mask")
      (net 253 "/USB-C Interface /DBG_VBUS") (pintype "passive"))
    (pad "B10" smd rect locked (at -2 -3.21) (size 0.3 0.7) (layers "F.Cu" "F.Paste" "F.Mask")
      (net 428 "unconnected-(J5-PadB10)") (pintype "passive+no_connect"))
    (pad "B11" smd rect locked (at -2.5 -3.21) (size 0.3 0.7) (layers "F.Cu" "F.Paste" "F.Mask")
      (net 427 "unconnected-(J5-PadB11)") (pintype "passive+no_connect"))
    (pad "B12" smd rect locked (at -3 -3.21) (size 0.3 0.7) (layers "F.Cu" "F.Paste" "F.Mask")
      (net 1 "GND") (pintype "passive"))
    (pad "SH" thru_hole oval locked (at -4.13 -3.001) (size 0.85 1.45) (drill oval 0.5 1.1) (layers *.Cu *.Mask)
      (net 1 "GND") (pintype "input"))
    (pad "SH" thru_hole oval locked (at -4.491 2.95) (size 0.85 1.45) (drill oval 0.5 1.1) (layers *.Cu *.Mask)
      (net 1 "GND") (pintype "input"))
    (pad "SH" thru_hole oval locked (at 4.128 -3.001) (size 0.85 1.45) (drill oval 0.5 1.1) (layers *.Cu *.Mask)
      (net 1 "GND") (pintype "input"))
    (pad "SH" thru_hole oval locked (at 4.49 2.95) (size 0.85 1.45) (drill oval 0.5 1.1) (layers *.Cu *.Mask)
      (net 1 "GND") (pintype "input"))
  )
	(footprint "sa800u-baseboard-hw-footprints:Nexperia_DFN-10_2.5x1mm_P0.5mm" (layer "F.Cu")
    (tedit 6215DC23)
    (at 129 141 180)
    (property "Author" "Antmicro")
    (property "License" "Apache-2.0")
    (property "MPN" "PUSB3F96X")
    (property "Manufacturer" "Nexperia")
    (property "Sheetfile" "usb-c-interface.kicad_sch")
    (property "Sheetname" "USB-C Interface ")
    (attr smd)
    (fp_text reference "D11" (at -2.29 -1 270) (layer "F.SilkS")
      (effects (font (size 0.7 0.7) (thickness 0.15)) (justify left bottom))
    )
    (fp_text value "PUSB3F96X_PASS" (at -0.016 1.705 180) (layer "F.Fab")
      (effects (font (size 0.7 0.7) (thickness 0.15)) (justify left bottom))
    )
    (fp_text user "${REFERENCE}" (at -1.367 3.704 180) (layer "F.Fab") hide
      (effects (font (size 0.7 0.7) (thickness 0.15)) (justify left bottom))
    )
    (fp_text user "Author: Antmicro" (at -1.367 4.905 180) (layer "F.Fab") hide
      (effects (font (size 0.7 0.7) (thickness 0.15)) (justify left bottom))
    )
    (fp_text user "License: Apache-2.0" (at -1.367 6.105 180) (layer "F.Fab") hide
      (effects (font (size 0.7 0.7) (thickness 0.15)) (justify left bottom))
    )
    (fp_line (start -1.266 -0.396) (end -1.266 0.405) (layer "F.SilkS") (width 0.15))
    (fp_line (start 1.233 0.405) (end 1.233 -0.396) (layer "F.SilkS") (width 0.15))
    (fp_circle (center -1.317 0.704) (end -1.266 0.704) (layer "F.SilkS") (width 0.15) (fill solid))
    (fp_rect (start -1.4 -0.7) (end 1.4 0.7) (layer "F.CrtYd") (width 0.05) (fill none))
    (pad "1" smd rect (at -1.016 0.392 180) (size 0.2 0.475) (layers "F.Cu" "F.Paste" "F.Mask")
      (net 229 "/USB-C Interface /DBG_USB_D_N") (pinfunction "CH1") (pintype "passive"))
    (pad "2" smd rect (at -0.517 0.392 180) (size 0.2 0.475) (layers "F.Cu" "F.Paste" "F.Mask")
      (net 230 "/USB-C Interface /DBG_USB_D_P") (pinfunction "CH2") (pintype "passive"))
    (pad "3" smd rect (at -0.016 0.392 180) (size 0.2 0.475) (layers "F.Cu" "F.Paste" "F.Mask")
      (net 1 "GND") (pinfunction "GND") (pintype "passive"))
    (pad "4" smd rect (at 0.482 0.392 180) (size 0.2 0.475) (layers "F.Cu" "F.Paste" "F.Mask")
      (net 253 "/USB-C Interface /DBG_VBUS") (pinfunction "CH3") (pintype "passive"))
    (pad "5" smd rect (at 0.982 0.392 180) (size 0.2 0.475) (layers "F.Cu" "F.Paste" "F.Mask")
      (net 253 "/USB-C Interface /DBG_VBUS") (pinfunction "CH4") (pintype "passive"))
    (pad "6" smd rect (at 0.982 -0.383) (size 0.2 0.475) (layers "F.Cu" "F.Paste" "F.Mask")
      (net 253 "/USB-C Interface /DBG_VBUS") (pinfunction "CH4") (pintype "passive"))
    (pad "7" smd rect (at 0.482 -0.383) (size 0.2 0.475) (layers "F.Cu" "F.Paste" "F.Mask")
      (net 253 "/USB-C Interface /DBG_VBUS") (pinfunction "CH3") (pintype "passive"))
    (pad "8" smd rect (at -0.016 -0.383) (size 0.2 0.475) (layers "F.Cu" "F.Paste" "F.Mask")
      (net 1 "GND") (pinfunction "GND") (pintype "passive"))
    (pad "9" smd rect (at -0.517 -0.383) (size 0.2 0.475) (layers "F.Cu" "F.Paste" "F.Mask")
      (net 230 "/USB-C Interface /DBG_USB_D_P") (pinfunction "CH2") (pintype "passive"))
    (pad "10" smd rect (at -1.016 -0.383) (size 0.2 0.475) (layers "F.Cu" "F.Paste" "F.Mask")
      (net 229 "/USB-C Interface /DBG_USB_D_N") (pinfunction "CH1") (pintype "passive"))
  )
	(footprint "sa800u-baseboard-hw-footprints:C_0402_1005Metric" (layer "F.Cu")
    (tedit 616D63CF)
    (at 111.59 93.8 90)
    (descr "Capacitor SMD 0402")
    (tags "capacitor SMD 0402")
    (property "Author" "Antmicro")
    (property "Dielectric" "X5R")
    (property "License" "Apache-2.0")
    (property "MPN" "GRM155R61H104KE14D")
    (property "Manufacturer" "Murata")
    (property "Sheetfile" "camera-interface.kicad_sch")
    (property "Sheetname" "Camera Interface")
    (property "Val" "100n")
    (property "Voltage" "50V")
    (attr smd)
    (fp_text reference "C110" (at -3.69 0.41 90) (layer "F.SilkS")
      (effects (font (size 0.7 0.7) (thickness 0.15)) (justify left bottom))
    )
    (fp_text value "C_100n_0402" (at 0 1.4 90) (layer "F.Fab")
      (effects (font (size 0.7 0.7) (thickness 0.15)) (justify left bottom))
    )
    (fp_text user "${REFERENCE}" (at -0.932 3.168 90) (layer "F.Fab") hide
      (effects (font (size 0.7 0.7) (thickness 0.15)) (justify left bottom))
    )
    (fp_text user "Author: Antmicro" (at -0.932 4.17 90) (layer "F.Fab") hide
      (effects (font (size 0.7 0.7) (thickness 0.15)) (justify left bottom))
    )
    (fp_text user "License: Apache-2.0" (at -0.932 5.17 90) (layer "F.Fab") hide
      (effects (font (size 0.7 0.7) (thickness 0.15)) (justify left bottom))
    )
    (fp_rect (start -0.94 -0.47) (end 0.94 0.47) (layer "F.CrtYd") (width 0.05) (fill none))
    (fp_rect (start -0.499 -0.249) (end 0.499 0.249) (layer "F.Fab") (width 0.15) (fill none))
    (pad "1" smd roundrect (at -0.484 0 90) (size 0.59 0.64) (layers "F.Cu" "F.Paste" "F.Mask") (roundrect_rratio 0.25)
      (net 231 "/Camera Interface/3V3_CAM") (pintype "passive"))
    (pad "2" smd roundrect (at 0.484 0 90) (size 0.59 0.64) (layers "F.Cu" "F.Paste" "F.Mask") (roundrect_rratio 0.25)
      (net 1 "GND") (pintype "passive"))
  )
	(footprint "sa800u-baseboard-hw-footprints:XSON-8_1x1.95mm_P0.5mm" (layer "F.Cu")
    (tedit 5DCD5522)
    (at 110.3 94.3)
    (property "Author" "Antmicro")
    (property "License" "Apache-2.0")
    (property "MPN" "NTS0102GT")
    (property "Manufacturer" "NXP")
    (property "Sheetfile" "camera-interface.kicad_sch")
    (property "Sheetname" "Camera Interface")
    (attr smd)
    (fp_text reference "U14" (at -3.07 2.1) (layer "F.SilkS")
      (effects (font (size 0.7 0.7) (thickness 0.15)) (justify left bottom))
    )
    (fp_text value "NTS0102_XSON" (at 0 2.2) (layer "F.Fab")
      (effects (font (size 0.7 0.7) (thickness 0.15)) (justify left bottom))
    )
    (fp_text user "License: Apache-2.0" (at -0.527 8.306) (layer "F.Fab") hide
      (effects (font (size 0.7 0.7) (thickness 0.15)) (justify left bottom))
    )
    (fp_text user "Author: Antmicro" (at -0.527 7.105) (layer "F.Fab") hide
      (effects (font (size 0.7 0.7) (thickness 0.15)) (justify left bottom))
    )
    (fp_text user "${REFERENCE}" (at -0.527 5.905) (layer "F.Fab") hide
      (effects (font (size 0.7 0.7) (thickness 0.15)) (justify left bottom))
    )
    (fp_line (start 0.5 1.1) (end -0.5 1.1) (layer "F.SilkS") (width 0.15))
    (fp_line (start -0.5 -1.1) (end 0.5 -1.1) (layer "F.SilkS") (width 0.15))
    (fp_circle (center -0.7 -0.95) (end -0.651 -0.95) (layer "F.SilkS") (width 0.15) (fill none))
    (fp_rect (start -0.8 -1.2) (end 0.8 1.2) (layer "F.CrtYd") (width 0.05) (fill none))
    (fp_line (start 0.5305 1) (end -0.5305 1) (layer "F.Fab") (width 0.15))
    (fp_line (start -0.5305 -1.001) (end 0.5305 -1.001) (layer "F.Fab") (width 0.15))
    (fp_line (start -0.5305 1) (end -0.5305 -1.001) (layer "F.Fab") (width 0.15))
    (fp_line (start 0.5305 -1.001) (end 0.5305 1) (layer "F.Fab") (width 0.15))
    (pad "1" smd rect (at -0.33 -0.75) (size 0.5 0.31) (layers "F.Cu" "F.Paste" "F.Mask")
      (net 296 "/Camera Interface/CCI0_I2C_SDA_3V3") (pinfunction "B_{2}") (pintype "bidirectional"))
    (pad "2" smd rect (at -0.33 -0.25) (size 0.5 0.31) (layers "F.Cu" "F.Paste" "F.Mask")
      (net 1 "GND") (pinfunction "GND") (pintype "power_in"))
    (pad "3" smd rect (at -0.33 0.25) (size 0.5 0.31) (layers "F.Cu" "F.Paste" "F.Mask")
      (net 139 "LVS1A_1V8") (pinfunction "VCC_{A}") (pintype "power_in"))
    (pad "4" smd rect (at -0.33 0.75) (size 0.5 0.31) (layers "F.Cu" "F.Paste" "F.Mask")
      (net 43 "CCI0_I2C_SDA") (pinfunction "A_{2}") (pintype "bidirectional"))
    (pad "5" smd rect (at 0.33 0.75 180) (size 0.5 0.31) (layers "F.Cu" "F.Paste" "F.Mask")
      (net 42 "CCI0_I2C_SCL") (pinfunction "A_{1}") (pintype "bidirectional"))
    (pad "6" smd rect (at 0.33 0.25 180) (size 0.5 0.31) (layers "F.Cu" "F.Paste" "F.Mask")
      (net 139 "LVS1A_1V8") (pinfunction "OE") (pintype "input"))
    (pad "7" smd rect (at 0.33 -0.25 180) (size 0.5 0.31) (layers "F.Cu" "F.Paste" "F.Mask")
      (net 231 "/Camera Interface/3V3_CAM") (pinfunction "VCC_{B}") (pintype "power_in"))
    (pad "8" smd rect (at 0.33 -0.75 180) (size 0.5 0.31) (layers "F.Cu" "F.Paste" "F.Mask")
      (net 294 "/Camera Interface/CCI0_I2C_SCL_3V3") (pinfunction "B_{1}") (pintype "bidirectional"))
  )
	(footprint "sa800u-baseboard-hw-footprints:XSON-8_1x1.95mm_P0.5mm" (layer "F.Cu")
    (tedit 5DCD5522)
    (at 113.83 94.3)
    (property "Author" "Antmicro")
    (property "License" "Apache-2.0")
    (property "MPN" "NTS0102GT")
    (property "Manufacturer" "NXP")
    (property "Sheetfile" "camera-interface.kicad_sch")
    (property "Sheetname" "Camera Interface")
    (attr smd)
    (fp_text reference "U13" (at 0.46 1.48) (layer "F.SilkS")
      (effects (font (size 0.7 0.7) (thickness 0.15)) (justify left bottom))
    )
    (fp_text value "NTS0102_XSON" (at 0 2.2) (layer "F.Fab")
      (effects (font (size 0.7 0.7) (thickness 0.15)) (justify left bottom))
    )
    (fp_text user "${REFERENCE}" (at -0.527 5.905) (layer "F.Fab") hide
      (effects (font (size 0.7 0.7) (thickness 0.15)) (justify left bottom))
    )
    (fp_text user "Author: Antmicro" (at -0.527 7.105) (layer "F.Fab") hide
      (effects (font (size 0.7 0.7) (thickness 0.15)) (justify left bottom))
    )
    (fp_text user "License: Apache-2.0" (at -0.527 8.306) (layer "F.Fab") hide
      (effects (font (size 0.7 0.7) (thickness 0.15)) (justify left bottom))
    )
    (fp_line (start 0.5 1.1) (end -0.5 1.1) (layer "F.SilkS") (width 0.15))
    (fp_line (start -0.5 -1.1) (end 0.5 -1.1) (layer "F.SilkS") (width 0.15))
    (fp_circle (center -0.7 -0.95) (end -0.651 -0.95) (layer "F.SilkS") (width 0.15) (fill none))
    (fp_rect (start -0.8 -1.2) (end 0.8 1.2) (layer "F.CrtYd") (width 0.05) (fill none))
    (fp_line (start -0.5305 -1.001) (end 0.5305 -1.001) (layer "F.Fab") (width 0.15))
    (fp_line (start 0.5305 -1.001) (end 0.5305 1) (layer "F.Fab") (width 0.15))
    (fp_line (start -0.5305 1) (end -0.5305 -1.001) (layer "F.Fab") (width 0.15))
    (fp_line (start 0.5305 1) (end -0.5305 1) (layer "F.Fab") (width 0.15))
    (pad "1" smd rect (at -0.33 -0.75) (size 0.5 0.31) (layers "F.Cu" "F.Paste" "F.Mask")
      (net 295 "/Camera Interface/CCI1_I2C_SDA_3V3") (pinfunction "B_{2}") (pintype "bidirectional"))
    (pad "2" smd rect (at -0.33 -0.25) (size 0.5 0.31) (layers "F.Cu" "F.Paste" "F.Mask")
      (net 1 "GND") (pinfunction "GND") (pintype "power_in"))
    (pad "3" smd rect (at -0.33 0.25) (size 0.5 0.31) (layers "F.Cu" "F.Paste" "F.Mask")
      (net 139 "LVS1A_1V8") (pinfunction "VCC_{A}") (pintype "power_in"))
    (pad "4" smd rect (at -0.33 0.75) (size 0.5 0.31) (layers "F.Cu" "F.Paste" "F.Mask")
      (net 45 "CCI1_I2C_SDA") (pinfunction "A_{2}") (pintype "bidirectional"))
    (pad "5" smd rect (at 0.33 0.75 180) (size 0.5 0.31) (layers "F.Cu" "F.Paste" "F.Mask")
      (net 44 "CCI1_I2C_SCL") (pinfunction "A_{1}") (pintype "bidirectional"))
    (pad "6" smd rect (at 0.33 0.25 180) (size 0.5 0.31) (layers "F.Cu" "F.Paste" "F.Mask")
      (net 139 "LVS1A_1V8") (pinfunction "OE") (pintype "input"))
    (pad "7" smd rect (at 0.33 -0.25 180) (size 0.5 0.31) (layers "F.Cu" "F.Paste" "F.Mask")
      (net 231 "/Camera Interface/3V3_CAM") (pinfunction "VCC_{B}") (pintype "power_in"))
    (pad "8" smd rect (at 0.33 -0.75 180) (size 0.5 0.31) (layers "F.Cu" "F.Paste" "F.Mask")
      (net 293 "/Camera Interface/CCI1_I2C_SCL_3V3") (pinfunction "B_{1}") (pintype "bidirectional"))
  )
)
